(kicad_pcb
	(version 20260206)
	(generator "pcbnew")
	(generator_version "10.0")
	(general
		(thickness 1.6)
		(legacy_teardrops no)
	)
	(paper "A4")
	(title_block
		(title "12092022_DA0F0TMDCD0_F0T_Management_Board_D_brd_V3_OCP.brd")
		(comment 1 "Grand Teton / footprints 1082-1087 of 1440")
	)
	(layers
		(0 "F.Cu" signal "TOP")
		(4 "In1.Cu" signal "GND")
		(6 "In2.Cu" signal "IN1")
		(8 "In3.Cu" signal "GND1")
		(10 "In4.Cu" signal "IN2")
		(12 "In5.Cu" signal "VCC")
		(14 "In6.Cu" signal "VCC1")
		(16 "In7.Cu" signal "IN3")
		(18 "In8.Cu" signal "GND2")
		(20 "In9.Cu" signal "IN4")
		(22 "In10.Cu" signal "GND3")
		(2 "B.Cu" signal "BOTTOM")
		(9 "F.Adhes" user "F.Adhesive")
		(11 "B.Adhes" user "B.Adhesive")
		(13 "F.Paste" user "Package Geometry/Pastemask Top")
		(15 "B.Paste" user "Package Geometry/Pastemask Bottom")
		(5 "F.SilkS" user "Ref Des/Silkscreen Top")
		(7 "B.SilkS" user "Ref Des/Silkscreen Bottom")
		(1 "F.Mask" user "Board Geometry/Soldermask Top")
		(3 "B.Mask" user "Board Geometry/Soldermask Bottom")
		(17 "Dwgs.User" user "User.Drawings")
		(19 "Cmts.User" user "User.Comments")
		(21 "Eco1.User" user "User.Eco1")
		(23 "Eco2.User" user "User.Eco2")
		(25 "Edge.Cuts" user "Board Geometry/Outline")
		(27 "Margin" user)
		(31 "F.CrtYd" user "Package Geometry/Place Bound Top")
		(29 "B.CrtYd" user "Package Geometry/Place Bound Bottom")
		(35 "F.Fab" user "Ref Des/Assembly Top")
		(33 "B.Fab" user "Ref Des/Assembly Bottom")
	)
	(footprint ""
		(layer "B.Cu")
		(at 52.27574 -69.397372 -90)
		(property "Reference" "C299"
			(at 0 0 90)
			(layer "B.SilkS")
			(hide yes)
			(effects
				(font
					(size 1.27 1.27)
				)
				(justify mirror)
			)
		)
		(property "Value" ""
			(at 0 0 90)
			(layer "B.Fab")
			(effects
				(font
					(size 1.27 1.27)
				)
				(justify mirror)
			)
		)
		(duplicate_pad_numbers_are_jumpers no)
		(fp_line
			(start -0.7874 0.4064)
			(end 0.7874 0.4064)
			(stroke
				(width 0.1524)
				(type default)
			)
			(layer "B.SilkS")
		)
		(fp_line
			(start 0.7874 0.4064)
			(end 0.7874 -0.4064)
			(stroke
				(width 0.1524)
				(type default)
			)
			(layer "B.SilkS")
		)
		(fp_line
			(start -0.7874 -0.4064)
			(end -0.7874 0.4064)
			(stroke
				(width 0.1524)
				(type default)
			)
			(layer "B.SilkS")
		)
		(fp_line
			(start 0.7874 -0.4064)
			(end -0.7874 -0.4064)
			(stroke
				(width 0.1524)
				(type default)
			)
			(layer "B.SilkS")
		)
		(fp_line
			(start -0.67945 0.3048)
			(end -0.120396 0.3048)
			(stroke
				(width 0.1)
				(type default)
			)
			(layer "B.Fab")
		)
		(fp_line
			(start -0.120396 0.3048)
			(end -0.120396 0.2794)
			(stroke
				(width 0.1)
				(type default)
			)
			(layer "B.Fab")
		)
		(fp_line
			(start 0.12065 0.3048)
			(end 0.67945 0.3048)
			(stroke
				(width 0.1)
				(type default)
			)
			(layer "B.Fab")
		)
		(fp_line
			(start 0.67945 0.3048)
			(end 0.67945 -0.305054)
			(stroke
				(width 0.1)
				(type default)
			)
			(layer "B.Fab")
		)
		(fp_line
			(start -0.120396 0.2794)
			(end 0.12065 0.2794)
			(stroke
				(width 0.1)
				(type default)
			)
			(layer "B.Fab")
		)
		(fp_line
			(start 0.12065 0.2794)
			(end 0.12065 0.3048)
			(stroke
				(width 0.1)
				(type default)
			)
			(layer "B.Fab")
		)
		(fp_line
			(start -0.12065 -0.2794)
			(end -0.12065 -0.3048)
			(stroke
				(width 0.1)
				(type default)
			)
			(layer "B.Fab")
		)
		(fp_line
			(start 0.12065 -0.2794)
			(end -0.12065 -0.2794)
			(stroke
				(width 0.1)
				(type default)
			)
			(layer "B.Fab")
		)
		(fp_line
			(start -0.67945 -0.3048)
			(end -0.67945 0.3048)
			(stroke
				(width 0.1)
				(type default)
			)
			(layer "B.Fab")
		)
		(fp_line
			(start -0.12065 -0.3048)
			(end -0.67945 -0.3048)
			(stroke
				(width 0.1)
				(type default)
			)
			(layer "B.Fab")
		)
		(fp_line
			(start 0.12065 -0.305054)
			(end 0.12065 -0.2794)
			(stroke
				(width 0.1)
				(type default)
			)
			(layer "B.Fab")
		)
		(fp_line
			(start 0.67945 -0.305054)
			(end 0.12065 -0.305054)
			(stroke
				(width 0.1)
				(type default)
			)
			(layer "B.Fab")
		)
		(pad "1" smd circle
			(at 0.40005 0 90)
			(size 0 0)
			(layers "B.Cu" "B.Mask" "B.Paste")
			(net "P3V3_SENSOR")
		)
		(pad "2" smd circle
			(at -0.40005 0 90)
			(size 0 0)
			(layers "B.Cu" "B.Mask" "B.Paste")
			(net "GND")
		)
	)
	(footprint ""
		(layer "B.Cu")
		(at 52.701444 -47.617126 -90)
		(property "Reference" "C91"
			(at 0 0 90)
			(layer "B.SilkS")
			(hide yes)
			(effects
				(font
					(size 1.27 1.27)
				)
				(justify mirror)
			)
		)
		(property "Value" ""
			(at 0 0 90)
			(layer "B.Fab")
			(effects
				(font
					(size 1.27 1.27)
				)
				(justify mirror)
			)
		)
		(duplicate_pad_numbers_are_jumpers no)
		(fp_line
			(start -0.7874 0.4064)
			(end 0.7874 0.4064)
			(stroke
				(width 0.1524)
				(type default)
			)
			(layer "B.SilkS")
		)
		(fp_line
			(start 0.7874 0.4064)
			(end 0.7874 -0.4064)
			(stroke
				(width 0.1524)
				(type default)
			)
			(layer "B.SilkS")
		)
		(fp_line
			(start -0.7874 -0.4064)
			(end -0.7874 0.4064)
			(stroke
				(width 0.1524)
				(type default)
			)
			(layer "B.SilkS")
		)
		(fp_line
			(start 0.7874 -0.4064)
			(end -0.7874 -0.4064)
			(stroke
				(width 0.1524)
				(type default)
			)
			(layer "B.SilkS")
		)
		(fp_line
			(start -0.67945 0.3048)
			(end -0.120396 0.3048)
			(stroke
				(width 0.1)
				(type default)
			)
			(layer "B.Fab")
		)
		(fp_line
			(start -0.120396 0.3048)
			(end -0.120396 0.2794)
			(stroke
				(width 0.1)
				(type default)
			)
			(layer "B.Fab")
		)
		(fp_line
			(start 0.12065 0.3048)
			(end 0.67945 0.3048)
			(stroke
				(width 0.1)
				(type default)
			)
			(layer "B.Fab")
		)
		(fp_line
			(start 0.67945 0.3048)
			(end 0.67945 -0.305054)
			(stroke
				(width 0.1)
				(type default)
			)
			(layer "B.Fab")
		)
		(fp_line
			(start -0.120396 0.2794)
			(end 0.12065 0.2794)
			(stroke
				(width 0.1)
				(type default)
			)
			(layer "B.Fab")
		)
		(fp_line
			(start 0.12065 0.2794)
			(end 0.12065 0.3048)
			(stroke
				(width 0.1)
				(type default)
			)
			(layer "B.Fab")
		)
		(fp_line
			(start -0.12065 -0.2794)
			(end -0.12065 -0.3048)
			(stroke
				(width 0.1)
				(type default)
			)
			(layer "B.Fab")
		)
		(fp_line
			(start 0.12065 -0.2794)
			(end -0.12065 -0.2794)
			(stroke
				(width 0.1)
				(type default)
			)
			(layer "B.Fab")
		)
		(fp_line
			(start -0.67945 -0.3048)
			(end -0.67945 0.3048)
			(stroke
				(width 0.1)
				(type default)
			)
			(layer "B.Fab")
		)
		(fp_line
			(start -0.12065 -0.3048)
			(end -0.67945 -0.3048)
			(stroke
				(width 0.1)
				(type default)
			)
			(layer "B.Fab")
		)
		(fp_line
			(start 0.12065 -0.305054)
			(end 0.12065 -0.2794)
			(stroke
				(width 0.1)
				(type default)
			)
			(layer "B.Fab")
		)
		(fp_line
			(start 0.67945 -0.305054)
			(end 0.12065 -0.305054)
			(stroke
				(width 0.1)
				(type default)
			)
			(layer "B.Fab")
		)
		(pad "1" smd circle
			(at 0.40005 0 90)
			(size 0 0)
			(layers "B.Cu" "B.Mask" "B.Paste")
			(net "P1V2_AUX")
		)
		(pad "2" smd circle
			(at -0.40005 0 90)
			(size 0 0)
			(layers "B.Cu" "B.Mask" "B.Paste")
			(net "GND")
		)
	)
	(footprint ""
		(layer "B.Cu")
		(at 37.311076 -38.822376 180)
		(property "Reference" "R207"
			(at 0 0 0)
			(layer "B.SilkS")
			(hide yes)
			(effects
				(font
					(size 1.27 1.27)
				)
				(justify mirror)
			)
		)
		(property "Value" ""
			(at 0 0 0)
			(layer "B.Fab")
			(effects
				(font
					(size 1.27 1.27)
				)
				(justify mirror)
			)
		)
		(duplicate_pad_numbers_are_jumpers no)
		(fp_line
			(start 0.7874 0.4064)
			(end 0.7874 -0.4064)
			(stroke
				(width 0.1524)
				(type default)
			)
			(layer "B.SilkS")
		)
		(fp_line
			(start 0.7874 -0.4064)
			(end -0.7874 -0.4064)
			(stroke
				(width 0.1524)
				(type default)
			)
			(layer "B.SilkS")
		)
		(fp_line
			(start -0.7874 0.4064)
			(end 0.7874 0.4064)
			(stroke
				(width 0.1524)
				(type default)
			)
			(layer "B.SilkS")
		)
		(fp_line
			(start -0.7874 -0.4064)
			(end -0.7874 0.4064)
			(stroke
				(width 0.1524)
				(type default)
			)
			(layer "B.SilkS")
		)
		(fp_line
			(start 0.67945 0.3048)
			(end 0.67945 -0.305054)
			(stroke
				(width 0.1)
				(type default)
			)
			(layer "B.Fab")
		)
		(fp_line
			(start 0.67945 -0.305054)
			(end 0.12065 -0.305054)
			(stroke
				(width 0.1)
				(type default)
			)
			(layer "B.Fab")
		)
		(fp_line
			(start 0.12065 0.3048)
			(end 0.67945 0.3048)
			(stroke
				(width 0.1)
				(type default)
			)
			(layer "B.Fab")
		)
		(fp_line
			(start 0.12065 0.2794)
			(end 0.12065 0.3048)
			(stroke
				(width 0.1)
				(type default)
			)
			(layer "B.Fab")
		)
		(fp_line
			(start 0.12065 -0.2794)
			(end -0.12065 -0.2794)
			(stroke
				(width 0.1)
				(type default)
			)
			(layer "B.Fab")
		)
		(fp_line
			(start 0.12065 -0.305054)
			(end 0.12065 -0.2794)
			(stroke
				(width 0.1)
				(type default)
			)
			(layer "B.Fab")
		)
		(fp_line
			(start -0.120396 0.3048)
			(end -0.120396 0.2794)
			(stroke
				(width 0.1)
				(type default)
			)
			(layer "B.Fab")
		)
		(fp_line
			(start -0.120396 0.2794)
			(end 0.12065 0.2794)
			(stroke
				(width 0.1)
				(type default)
			)
			(layer "B.Fab")
		)
		(fp_line
			(start -0.12065 -0.2794)
			(end -0.12065 -0.3048)
			(stroke
				(width 0.1)
				(type default)
			)
			(layer "B.Fab")
		)
		(fp_line
			(start -0.12065 -0.3048)
			(end -0.67945 -0.3048)
			(stroke
				(width 0.1)
				(type default)
			)
			(layer "B.Fab")
		)
		(fp_line
			(start -0.67945 0.3048)
			(end -0.120396 0.3048)
			(stroke
				(width 0.1)
				(type default)
			)
			(layer "B.Fab")
		)
		(fp_line
			(start -0.67945 -0.3048)
			(end -0.67945 0.3048)
			(stroke
				(width 0.1)
				(type default)
			)
			(layer "B.Fab")
		)
		(pad "1" smd circle
			(at 0.40005 0)
			(size 0 0)
			(layers "B.Cu" "B.Mask" "B.Paste")
			(net "P3V3_AUX")
		)
		(pad "2" smd circle
			(at -0.40005 0)
			(size 0 0)
			(layers "B.Cu" "B.Mask" "B.Paste")
			(net "P3V3_P1V8_SD1VDD")
		)
	)
	(footprint ""
		(layer "B.Cu")
		(at 46.96206 -61.97981 90)
		(property "Reference" "C136"
			(at 0 0 90)
			(layer "B.SilkS")
			(hide yes)
			(effects
				(font
					(size 1.27 1.27)
				)
				(justify mirror)
			)
		)
		(property "Value" ""
			(at 0 0 90)
			(layer "B.Fab")
			(effects
				(font
					(size 1.27 1.27)
				)
				(justify mirror)
			)
		)
		(duplicate_pad_numbers_are_jumpers no)
		(fp_line
			(start 0.7874 -0.4064)
			(end -0.7874 -0.4064)
			(stroke
				(width 0.1524)
				(type default)
			)
			(layer "B.SilkS")
		)
		(fp_line
			(start -0.7874 -0.4064)
			(end -0.7874 0.4064)
			(stroke
				(width 0.1524)
				(type default)
			)
			(layer "B.SilkS")
		)
		(fp_line
			(start 0.7874 0.4064)
			(end 0.7874 -0.4064)
			(stroke
				(width 0.1524)
				(type default)
			)
			(layer "B.SilkS")
		)
		(fp_line
			(start -0.7874 0.4064)
			(end 0.7874 0.4064)
			(stroke
				(width 0.1524)
				(type default)
			)
			(layer "B.SilkS")
		)
		(fp_line
			(start 0.67945 -0.305054)
			(end 0.12065 -0.305054)
			(stroke
				(width 0.1)
				(type default)
			)
			(layer "B.Fab")
		)
		(fp_line
			(start 0.12065 -0.305054)
			(end 0.12065 -0.2794)
			(stroke
				(width 0.1)
				(type default)
			)
			(layer "B.Fab")
		)
		(fp_line
			(start -0.12065 -0.3048)
			(end -0.67945 -0.3048)
			(stroke
				(width 0.1)
				(type default)
			)
			(layer "B.Fab")
		)
		(fp_line
			(start -0.67945 -0.3048)
			(end -0.67945 0.3048)
			(stroke
				(width 0.1)
				(type default)
			)
			(layer "B.Fab")
		)
		(fp_line
			(start 0.12065 -0.2794)
			(end -0.12065 -0.2794)
			(stroke
				(width 0.1)
				(type default)
			)
			(layer "B.Fab")
		)
		(fp_line
			(start -0.12065 -0.2794)
			(end -0.12065 -0.3048)
			(stroke
				(width 0.1)
				(type default)
			)
			(layer "B.Fab")
		)
		(fp_line
			(start 0.12065 0.2794)
			(end 0.12065 0.3048)
			(stroke
				(width 0.1)
				(type default)
			)
			(layer "B.Fab")
		)
		(fp_line
			(start -0.120396 0.2794)
			(end 0.12065 0.2794)
			(stroke
				(width 0.1)
				(type default)
			)
			(layer "B.Fab")
		)
		(fp_line
			(start 0.67945 0.3048)
			(end 0.67945 -0.305054)
			(stroke
				(width 0.1)
				(type default)
			)
			(layer "B.Fab")
		)
		(fp_line
			(start 0.12065 0.3048)
			(end 0.67945 0.3048)
			(stroke
				(width 0.1)
				(type default)
			)
			(layer "B.Fab")
		)
		(fp_line
			(start -0.120396 0.3048)
			(end -0.120396 0.2794)
			(stroke
				(width 0.1)
				(type default)
			)
			(layer "B.Fab")
		)
		(fp_line
			(start -0.67945 0.3048)
			(end -0.120396 0.3048)
			(stroke
				(width 0.1)
				(type default)
			)
			(layer "B.Fab")
		)
		(pad "1" smd circle
			(at 0.40005 0 270)
			(size 0 0)
			(layers "B.Cu" "B.Mask" "B.Paste")
			(net "GND")
		)
		(pad "2" smd circle
			(at -0.40005 0 270)
			(size 0 0)
			(layers "B.Cu" "B.Mask" "B.Paste")
			(net "A_BMC_ADCVREFP0")
		)
	)
	(footprint ""
		(layer "B.Cu")
		(at 84.452968 -99.238054 180)
		(property "Reference" "C248"
			(at 0 0 0)
			(layer "B.SilkS")
			(hide yes)
			(effects
				(font
					(size 1.27 1.27)
				)
				(justify mirror)
			)
		)
		(property "Value" ""
			(at 0 0 0)
			(layer "B.Fab")
			(effects
				(font
					(size 1.27 1.27)
				)
				(justify mirror)
			)
		)
		(duplicate_pad_numbers_are_jumpers no)
		(fp_line
			(start 0.7874 0.4064)
			(end 0.7874 -0.4064)
			(stroke
				(width 0.1524)
				(type default)
			)
			(layer "B.SilkS")
		)
		(fp_line
			(start 0.7874 -0.4064)
			(end -0.7874 -0.4064)
			(stroke
				(width 0.1524)
				(type default)
			)
			(layer "B.SilkS")
		)
		(fp_line
			(start -0.7874 0.4064)
			(end 0.7874 0.4064)
			(stroke
				(width 0.1524)
				(type default)
			)
			(layer "B.SilkS")
		)
		(fp_line
			(start -0.7874 -0.4064)
			(end -0.7874 0.4064)
			(stroke
				(width 0.1524)
				(type default)
			)
			(layer "B.SilkS")
		)
		(fp_line
			(start 0.67945 0.3048)
			(end 0.67945 -0.305054)
			(stroke
				(width 0.1)
				(type default)
			)
			(layer "B.Fab")
		)
		(fp_line
			(start 0.67945 -0.305054)
			(end 0.12065 -0.305054)
			(stroke
				(width 0.1)
				(type default)
			)
			(layer "B.Fab")
		)
		(fp_line
			(start 0.12065 0.3048)
			(end 0.67945 0.3048)
			(stroke
				(width 0.1)
				(type default)
			)
			(layer "B.Fab")
		)
		(fp_line
			(start 0.12065 0.2794)
			(end 0.12065 0.3048)
			(stroke
				(width 0.1)
				(type default)
			)
			(layer "B.Fab")
		)
		(fp_line
			(start 0.12065 -0.2794)
			(end -0.12065 -0.2794)
			(stroke
				(width 0.1)
				(type default)
			)
			(layer "B.Fab")
		)
		(fp_line
			(start 0.12065 -0.305054)
			(end 0.12065 -0.2794)
			(stroke
				(width 0.1)
				(type default)
			)
			(layer "B.Fab")
		)
		(fp_line
			(start -0.120396 0.3048)
			(end -0.120396 0.2794)
			(stroke
				(width 0.1)
				(type default)
			)
			(layer "B.Fab")
		)
		(fp_line
			(start -0.120396 0.2794)
			(end 0.12065 0.2794)
			(stroke
				(width 0.1)
				(type default)
			)
			(layer "B.Fab")
		)
		(fp_line
			(start -0.12065 -0.2794)
			(end -0.12065 -0.3048)
			(stroke
				(width 0.1)
				(type default)
			)
			(layer "B.Fab")
		)
		(fp_line
			(start -0.12065 -0.3048)
			(end -0.67945 -0.3048)
			(stroke
				(width 0.1)
				(type default)
			)
			(layer "B.Fab")
		)
		(fp_line
			(start -0.67945 0.3048)
			(end -0.120396 0.3048)
			(stroke
				(width 0.1)
				(type default)
			)
			(layer "B.Fab")
		)
		(fp_line
			(start -0.67945 -0.3048)
			(end -0.67945 0.3048)
			(stroke
				(width 0.1)
				(type default)
			)
			(layer "B.Fab")
		)
		(pad "1" smd circle
			(at 0.40005 0)
			(size 0 0)
			(layers "B.Cu" "B.Mask" "B.Paste")
			(net "P3V3_AUX")
		)
		(pad "2" smd circle
			(at -0.40005 0)
			(size 0 0)
			(layers "B.Cu" "B.Mask" "B.Paste")
			(net "GND")
		)
	)
	(footprint ""
		(layer "B.Cu")
		(at 54.880764 -52.938934 90)
		(property "Reference" "C121"
			(at 0 0 90)
			(layer "B.SilkS")
			(hide yes)
			(effects
				(font
					(size 1.27 1.27)
				)
				(justify mirror)
			)
		)
		(property "Value" ""
			(at 0 0 90)
			(layer "B.Fab")
			(effects
				(font
					(size 1.27 1.27)
				)
				(justify mirror)
			)
		)
		(duplicate_pad_numbers_are_jumpers no)
		(fp_line
			(start 1.2954 -0.5842)
			(end -1.2954 -0.5842)
			(stroke
				(width 0.1524)
				(type default)
			)
			(layer "B.SilkS")
		)
		(fp_line
			(start 0 -0.5842)
			(end 0 0.5842)
			(stroke
				(width 0.1524)
				(type default)
			)
			(layer "B.SilkS")
		)
		(fp_line
			(start -1.2954 -0.5842)
			(end -1.2954 0.5842)
			(stroke
				(width 0.1524)
				(type default)
			)
			(layer "B.SilkS")
		)
		(fp_line
			(start 1.2954 0.5842)
			(end 1.2954 -0.5842)
			(stroke
				(width 0.1524)
				(type default)
			)
			(layer "B.SilkS")
		)
		(fp_line
			(start -1.2954 0.5842)
			(end 1.2954 0.5842)
			(stroke
				(width 0.1524)
				(type default)
			)
			(layer "B.SilkS")
		)
		(fp_line
			(start 0.8636 -0.4572)
			(end -0.8636 -0.4572)
			(stroke
				(width 0.1)
				(type default)
			)
			(layer "B.Fab")
		)
		(fp_line
			(start -0.8636 -0.4572)
			(end -0.8636 -0.4064)
			(stroke
				(width 0.1)
				(type default)
			)
			(layer "B.Fab")
		)
		(fp_line
			(start 1.1938 -0.4064)
			(end 0.8636 -0.4064)
			(stroke
				(width 0.1)
				(type default)
			)
			(layer "B.Fab")
		)
		(fp_line
			(start 0.8636 -0.4064)
			(end 0.8636 -0.4572)
			(stroke
				(width 0.1)
				(type default)
			)
			(layer "B.Fab")
		)
		(fp_line
			(start -0.8636 -0.4064)
			(end -1.1938 -0.4064)
			(stroke
				(width 0.1)
				(type default)
			)
			(layer "B.Fab")
		)
		(fp_line
			(start -1.1938 -0.4064)
			(end -1.1938 0.4064)
			(stroke
				(width 0.1)
				(type default)
			)
			(layer "B.Fab")
		)
		(fp_line
			(start 1.1938 0.4064)
			(end 1.1938 -0.4064)
			(stroke
				(width 0.1)
				(type default)
			)
			(layer "B.Fab")
		)
		(fp_line
			(start 0.8636 0.4064)
			(end 1.1938 0.4064)
			(stroke
				(width 0.1)
				(type default)
			)
			(layer "B.Fab")
		)
		(fp_line
			(start -0.8636 0.4064)
			(end -0.8636 0.4572)
			(stroke
				(width 0.1)
				(type default)
			)
			(layer "B.Fab")
		)
		(fp_line
			(start -1.1938 0.4064)
			(end -0.8636 0.4064)
			(stroke
				(width 0.1)
				(type default)
			)
			(layer "B.Fab")
		)
		(fp_line
			(start 0.8636 0.4572)
			(end 0.8636 0.4064)
			(stroke
				(width 0.1)
				(type default)
			)
			(layer "B.Fab")
		)
		(fp_line
			(start -0.8636 0.4572)
			(end 0.8636 0.4572)
			(stroke
				(width 0.1)
				(type default)
			)
			(layer "B.Fab")
		)
		(pad "1" smd rect
			(at 0.7366 0)
			(size 0.7112 0.8128)
			(layers "B.Cu" "B.Mask" "B.Paste")
			(net "P1V8_AUX")
		)
		(pad "2" smd rect
			(at -0.7366 0)
			(size 0.7112 0.8128)
			(layers "B.Cu" "B.Mask" "B.Paste")
			(net "GND")
		)
	)
)
